(kicad_pcb
	(version 20260206)
	(generator "pcbnew")
	(generator_version "10.0")
	(general
		(thickness 1.6)
		(legacy_teardrops no)
	)
	(paper "A4")
	(title_block
		(title "peb — Lightning_PEB_BRD.brd")
		(comment 1 "Lightning (Wiwynn / Facebook NVMe JBOF) / footprints 2336-2342 of 2563")
	)
	(layers
		(0 "F.Cu" signal "TOP")
		(4 "In1.Cu" signal "L2GND")
		(6 "In2.Cu" signal "L3")
		(8 "In3.Cu" signal "L4VCC")
		(10 "In4.Cu" signal "L5VCC")
		(12 "In5.Cu" signal "L6")
		(14 "In6.Cu" signal "L7GND")
		(2 "B.Cu" signal "BOTTOM")
		(9 "F.Adhes" user "F.Adhesive")
		(11 "B.Adhes" user "B.Adhesive")
		(13 "F.Paste" user "Package Geometry/Pastemask Top")
		(15 "B.Paste" user "Package Geometry/Pastemask Bottom")
		(5 "F.SilkS" user "Ref Des/Silkscreen Top")
		(7 "B.SilkS" user "Ref Des/Silkscreen Bottom")
		(1 "F.Mask" user "Board Geometry/Soldermask Top")
		(3 "B.Mask" user "Board Geometry/Soldermask Bottom")
		(17 "Dwgs.User" user "User.Drawings")
		(19 "Cmts.User" user "User.Comments")
		(21 "Eco1.User" user "User.Eco1")
		(23 "Eco2.User" user "User.Eco2")
		(25 "Edge.Cuts" user "Board Geometry/Outline")
		(27 "Margin" user)
		(31 "F.CrtYd" user "Package Geometry/Place Bound Top")
		(29 "B.CrtYd" user "Package Geometry/Place Bound Bottom")
		(35 "F.Fab" user "Ref Des/Assembly Top")
		(33 "B.Fab" user "Ref Des/Assembly Bottom")
	)
	(footprint ""
		(layer "B.Cu")
		(at 240.538 -20.447)
		(property "Reference" "R807"
			(at 0 0 0)
			(layer "B.SilkS")
			(hide yes)
			(effects
				(font
					(size 1.27 1.27)
				)
				(justify mirror)
			)
		)
		(property "Value" "4K7R2F-GP"
			(at -0.064008 -3.993896 0)
			(unlocked yes)
			(layer "B.Fab")
			(hide yes)
			(effects
				(font
					(size 1.016 1.016)
					(thickness 0.1524)
				)
				(justify mirror)
			)
		)
		(property "Device Type" "R402H16"
			(at -0.064008 -5.517896 0)
			(unlocked yes)
			(layer "B.Fab")
			(hide yes)
			(effects
				(font
					(size 1.016 1.016)
					(thickness 0.1524)
				)
				(justify mirror)
			)
		)
		(duplicate_pad_numbers_are_jumpers no)
		(fp_line
			(start -0.508 -0.9398)
			(end 0.508 -0.9398)
			(stroke
				(width 0.1524)
				(type default)
			)
			(layer "B.SilkS")
		)
		(fp_line
			(start 0.508 -0.9398)
			(end 0.508 0.9398)
			(stroke
				(width 0.1524)
				(type default)
			)
			(layer "B.SilkS")
		)
		(fp_rect
			(start 0.508 0.9398)
			(end -0.508 -0.9398)
			(stroke
				(width 0)
				(type default)
			)
			(fill no)
			(layer "B.CrtYd")
		)
		(fp_rect
			(start 0.508 0.9398)
			(end -0.508 -0.9398)
			(stroke
				(width 0)
				(type default)
			)
			(fill no)
			(layer "B.Fab")
		)
		(pad "1" smd custom
			(at 0 -0.4445 180)
			(size 0.1397 0.1397)
			(layers "B.Cu" "B.Mask" "B.Paste")
			(net "BOOTSTRAP3")
			(options
				(clearance outline)
				(anchor circle)
			)
			(primitives
				(gr_poly
					(pts
						(arc
							(start -0.1778 0.2794)
							(mid -0.249642 0.249642)
							(end -0.2794 0.1778)
						)
						(arc
							(start -0.2794 -0.1778)
							(mid -0.249642 -0.249642)
							(end -0.1778 -0.2794)
						)
						(arc
							(start 0.1778 -0.2794)
							(mid 0.249642 -0.249642)
							(end 0.2794 -0.1778)
						)
						(arc
							(start 0.2794 0.1778)
							(mid 0.249642 0.249642)
							(end 0.1778 0.2794)
						)
					)
					(width 0)
					(fill yes)
				)
			)
		)
		(pad "2" smd custom
			(at 0 0.4445 180)
			(size 0.1397 0.1397)
			(layers "B.Cu" "B.Mask" "B.Paste")
			(net "DUT_VDDO")
			(options
				(clearance outline)
				(anchor circle)
			)
			(primitives
				(gr_poly
					(pts
						(arc
							(start -0.1778 0.2794)
							(mid -0.249642 0.249642)
							(end -0.2794 0.1778)
						)
						(arc
							(start -0.2794 -0.1778)
							(mid -0.249642 -0.249642)
							(end -0.1778 -0.2794)
						)
						(arc
							(start 0.1778 -0.2794)
							(mid 0.249642 -0.249642)
							(end 0.2794 -0.1778)
						)
						(arc
							(start 0.2794 0.1778)
							(mid 0.249642 0.249642)
							(end 0.1778 0.2794)
						)
					)
					(width 0)
					(fill yes)
				)
			)
		)
	)
	(footprint ""
		(layer "B.Cu")
		(at 62.357 -34.036 180)
		(property "Reference" "PR35"
			(at 0 0 0)
			(layer "B.SilkS")
			(hide yes)
			(effects
				(font
					(size 1.27 1.27)
				)
				(justify mirror)
			)
		)
		(property "Value" "619KR2F-GP"
			(at -0.064008 -3.993896 180)
			(unlocked yes)
			(layer "B.Fab")
			(hide yes)
			(effects
				(font
					(size 1.016 1.016)
					(thickness 0.1524)
				)
				(justify mirror)
			)
		)
		(property "Device Type" "R402H16"
			(at -0.064008 -5.517896 180)
			(unlocked yes)
			(layer "B.Fab")
			(hide yes)
			(effects
				(font
					(size 1.016 1.016)
					(thickness 0.1524)
				)
				(justify mirror)
			)
		)
		(duplicate_pad_numbers_are_jumpers no)
		(fp_line
			(start 0.508 -0.9398)
			(end 0.508 0.9398)
			(stroke
				(width 0.1524)
				(type default)
			)
			(layer "B.SilkS")
		)
		(fp_line
			(start -0.508 -0.9398)
			(end 0.508 -0.9398)
			(stroke
				(width 0.1524)
				(type default)
			)
			(layer "B.SilkS")
		)
		(fp_rect
			(start 0.508 0.9398)
			(end -0.508 -0.9398)
			(stroke
				(width 0)
				(type default)
			)
			(fill no)
			(layer "B.CrtYd")
		)
		(fp_rect
			(start 0.508 0.9398)
			(end -0.508 -0.9398)
			(stroke
				(width 0)
				(type default)
			)
			(fill no)
			(layer "B.Fab")
		)
		(pad "1" smd custom
			(at 0 -0.4445)
			(size 0.1397 0.1397)
			(layers "B.Cu" "B.Mask" "B.Paste")
			(net "AGND_P3V3_STBY")
			(options
				(clearance outline)
				(anchor circle)
			)
			(primitives
				(gr_poly
					(pts
						(arc
							(start -0.1778 0.2794)
							(mid -0.249642 0.249642)
							(end -0.2794 0.1778)
						)
						(arc
							(start -0.2794 -0.1778)
							(mid -0.249642 -0.249642)
							(end -0.1778 -0.2794)
						)
						(arc
							(start 0.1778 -0.2794)
							(mid 0.249642 -0.249642)
							(end 0.2794 -0.1778)
						)
						(arc
							(start 0.2794 0.1778)
							(mid 0.249642 0.249642)
							(end 0.1778 0.2794)
						)
					)
					(width 0)
					(fill yes)
				)
			)
		)
		(pad "2" smd custom
			(at 0 0.4445)
			(size 0.1397 0.1397)
			(layers "B.Cu" "B.Mask" "B.Paste")
			(net "P3V3_STBY_RF")
			(options
				(clearance outline)
				(anchor circle)
			)
			(primitives
				(gr_poly
					(pts
						(arc
							(start -0.1778 0.2794)
							(mid -0.249642 0.249642)
							(end -0.2794 0.1778)
						)
						(arc
							(start -0.2794 -0.1778)
							(mid -0.249642 -0.249642)
							(end -0.1778 -0.2794)
						)
						(arc
							(start 0.1778 -0.2794)
							(mid 0.249642 -0.249642)
							(end 0.2794 -0.1778)
						)
						(arc
							(start 0.2794 0.1778)
							(mid 0.249642 0.249642)
							(end 0.1778 0.2794)
						)
					)
					(width 0)
					(fill yes)
				)
			)
		)
	)
	(footprint ""
		(layer "B.Cu")
		(at 53.361844 -51.5874)
		(property "Reference" "R686"
			(at 0 0 0)
			(layer "B.SilkS")
			(hide yes)
			(effects
				(font
					(size 1.27 1.27)
				)
				(justify mirror)
			)
		)
		(property "Value" "0R2J-2-GP"
			(at -0.064008 -3.993896 0)
			(unlocked yes)
			(layer "B.Fab")
			(hide yes)
			(effects
				(font
					(size 1.016 1.016)
					(thickness 0.1524)
				)
				(justify mirror)
			)
		)
		(property "Device Type" "R402H16"
			(at -0.064008 -5.517896 0)
			(unlocked yes)
			(layer "B.Fab")
			(hide yes)
			(effects
				(font
					(size 1.016 1.016)
					(thickness 0.1524)
				)
				(justify mirror)
			)
		)
		(duplicate_pad_numbers_are_jumpers no)
		(fp_line
			(start -0.508 -0.9398)
			(end 0.508 -0.9398)
			(stroke
				(width 0.1524)
				(type default)
			)
			(layer "B.SilkS")
		)
		(fp_line
			(start 0.508 -0.9398)
			(end 0.508 0.9398)
			(stroke
				(width 0.1524)
				(type default)
			)
			(layer "B.SilkS")
		)
		(fp_rect
			(start 0.508 0.9398)
			(end -0.508 -0.9398)
			(stroke
				(width 0)
				(type default)
			)
			(fill no)
			(layer "B.CrtYd")
		)
		(fp_rect
			(start 0.508 0.9398)
			(end -0.508 -0.9398)
			(stroke
				(width 0)
				(type default)
			)
			(fill no)
			(layer "B.Fab")
		)
		(pad "1" smd custom
			(at 0 -0.4445 180)
			(size 0.1397 0.1397)
			(layers "B.Cu" "B.Mask" "B.Paste")
			(net "USB_P2_DP")
			(options
				(clearance outline)
				(anchor circle)
			)
			(primitives
				(gr_poly
					(pts
						(arc
							(start -0.1778 0.2794)
							(mid -0.249642 0.249642)
							(end -0.2794 0.1778)
						)
						(arc
							(start -0.2794 -0.1778)
							(mid -0.249642 -0.249642)
							(end -0.1778 -0.2794)
						)
						(arc
							(start 0.1778 -0.2794)
							(mid 0.249642 -0.249642)
							(end 0.2794 -0.1778)
						)
						(arc
							(start 0.2794 0.1778)
							(mid 0.249642 0.249642)
							(end 0.1778 0.2794)
						)
					)
					(width 0)
					(fill yes)
				)
			)
		)
		(pad "2" smd custom
			(at 0 0.4445 180)
			(size 0.1397 0.1397)
			(layers "B.Cu" "B.Mask" "B.Paste")
			(net "USB_DP_R")
			(options
				(clearance outline)
				(anchor circle)
			)
			(primitives
				(gr_poly
					(pts
						(arc
							(start -0.1778 0.2794)
							(mid -0.249642 0.249642)
							(end -0.2794 0.1778)
						)
						(arc
							(start -0.2794 -0.1778)
							(mid -0.249642 -0.249642)
							(end -0.1778 -0.2794)
						)
						(arc
							(start 0.1778 -0.2794)
							(mid 0.249642 -0.249642)
							(end 0.2794 -0.1778)
						)
						(arc
							(start 0.2794 0.1778)
							(mid 0.249642 0.249642)
							(end 0.1778 0.2794)
						)
					)
					(width 0)
					(fill yes)
				)
			)
		)
	)
	(footprint ""
		(layer "B.Cu")
		(at 20.945348 -141.89456 90)
		(property "Reference" "R743"
			(at 0 0 90)
			(layer "B.SilkS")
			(hide yes)
			(effects
				(font
					(size 1.27 1.27)
				)
				(justify mirror)
			)
		)
		(property "Value" "0R2J-2-GP"
			(at -0.064008 -3.993896 90)
			(unlocked yes)
			(layer "B.Fab")
			(hide yes)
			(effects
				(font
					(size 1.016 1.016)
					(thickness 0.1524)
				)
				(justify mirror)
			)
		)
		(property "Device Type" "R402H16"
			(at -0.064008 -5.517896 90)
			(unlocked yes)
			(layer "B.Fab")
			(hide yes)
			(effects
				(font
					(size 1.016 1.016)
					(thickness 0.1524)
				)
				(justify mirror)
			)
		)
		(duplicate_pad_numbers_are_jumpers no)
		(fp_line
			(start 0.508 -0.9398)
			(end 0.508 0.9398)
			(stroke
				(width 0.1524)
				(type default)
			)
			(layer "B.SilkS")
		)
		(fp_line
			(start -0.508 -0.9398)
			(end 0.508 -0.9398)
			(stroke
				(width 0.1524)
				(type default)
			)
			(layer "B.SilkS")
		)
		(fp_rect
			(start 0.508 0.9398)
			(end -0.508 -0.9398)
			(stroke
				(width 0)
				(type default)
			)
			(fill no)
			(layer "B.CrtYd")
		)
		(fp_rect
			(start 0.508 0.9398)
			(end -0.508 -0.9398)
			(stroke
				(width 0)
				(type default)
			)
			(fill no)
			(layer "B.Fab")
		)
		(pad "1" smd custom
			(at 0 -0.4445 270)
			(size 0.1397 0.1397)
			(layers "B.Cu" "B.Mask" "B.Paste")
			(net "RST_BMC_EXTRST_N")
			(options
				(clearance outline)
				(anchor circle)
			)
			(primitives
				(gr_poly
					(pts
						(arc
							(start -0.1778 0.2794)
							(mid -0.249642 0.249642)
							(end -0.2794 0.1778)
						)
						(arc
							(start -0.2794 -0.1778)
							(mid -0.249642 -0.249642)
							(end -0.1778 -0.2794)
						)
						(arc
							(start 0.1778 -0.2794)
							(mid 0.249642 -0.249642)
							(end 0.2794 -0.1778)
						)
						(arc
							(start 0.2794 0.1778)
							(mid 0.249642 0.249642)
							(end 0.1778 0.2794)
						)
					)
					(width 0)
					(fill yes)
				)
			)
		)
		(pad "2" smd custom
			(at 0 0.4445 270)
			(size 0.1397 0.1397)
			(layers "B.Cu" "B.Mask" "B.Paste")
			(net "BMC0_SRST_N")
			(options
				(clearance outline)
				(anchor circle)
			)
			(primitives
				(gr_poly
					(pts
						(arc
							(start -0.1778 0.2794)
							(mid -0.249642 0.249642)
							(end -0.2794 0.1778)
						)
						(arc
							(start -0.2794 -0.1778)
							(mid -0.249642 -0.249642)
							(end -0.1778 -0.2794)
						)
						(arc
							(start 0.1778 -0.2794)
							(mid 0.249642 -0.249642)
							(end 0.2794 -0.1778)
						)
						(arc
							(start 0.2794 0.1778)
							(mid 0.249642 0.249642)
							(end 0.1778 0.2794)
						)
					)
					(width 0)
					(fill yes)
				)
			)
		)
	)
	(footprint ""
		(layer "B.Cu")
		(at 347.0402 -64.643 -90)
		(property "Reference" "PR150"
			(at 0 0 90)
			(layer "B.SilkS")
			(hide yes)
			(effects
				(font
					(size 1.27 1.27)
				)
				(justify mirror)
			)
		)
		(property "Value" "0R3J-0-U-GP"
			(at 0.0254 -2.5146 270)
			(unlocked yes)
			(layer "B.Fab")
			(hide yes)
			(effects
				(font
					(size 1.016 1.016)
					(thickness 0.1524)
				)
				(justify mirror)
			)
		)
		(property "Device Type" "R603H22"
			(at 0.0254 -4.0386 270)
			(unlocked yes)
			(layer "B.Fab")
			(hide yes)
			(effects
				(font
					(size 1.016 1.016)
					(thickness 0.1524)
				)
				(justify mirror)
			)
		)
		(duplicate_pad_numbers_are_jumpers no)
		(fp_line
			(start -0.2032 0)
			(end -0.4826 0)
			(stroke
				(width 0.2032)
				(type default)
			)
			(layer "B.SilkS")
		)
		(fp_line
			(start 0.4826 0)
			(end 0.2032 0)
			(stroke
				(width 0.2032)
				(type default)
			)
			(layer "B.SilkS")
		)
		(fp_rect
			(start 0.5842 1.3335)
			(end -0.5842 -1.3335)
			(stroke
				(width 0)
				(type default)
			)
			(fill no)
			(layer "B.CrtYd")
		)
		(fp_rect
			(start 0.5842 1.3335)
			(end -0.5842 -1.3335)
			(stroke
				(width 0)
				(type default)
			)
			(fill no)
			(layer "B.Fab")
		)
		(pad "1" smd custom
			(at 0 -0.762 90)
			(size 0.2159 0.2159)
			(layers "B.Cu" "B.Mask" "B.Paste")
			(net "P12V")
			(options
				(clearance outline)
				(anchor circle)
			)
			(primitives
				(gr_poly
					(pts
						(arc
							(start -0.3302 0.4318)
							(mid -0.402042 0.402042)
							(end -0.4318 0.3302)
						)
						(arc
							(start -0.4318 -0.3302)
							(mid -0.402042 -0.402042)
							(end -0.3302 -0.4318)
						)
						(arc
							(start 0.3302 -0.4318)
							(mid 0.402042 -0.402042)
							(end 0.4318 -0.3302)
						)
						(arc
							(start 0.4318 0.3302)
							(mid 0.402042 0.402042)
							(end 0.3302 0.4318)
						)
					)
					(width 0)
					(fill yes)
				)
			)
		)
		(pad "2" smd custom
			(at 0 0.762 90)
			(size 0.2159 0.2159)
			(layers "B.Cu" "B.Mask" "B.Paste")
			(net "P0V9_E_VDD")
			(options
				(clearance outline)
				(anchor circle)
			)
			(primitives
				(gr_poly
					(pts
						(arc
							(start -0.3302 0.4318)
							(mid -0.402042 0.402042)
							(end -0.4318 0.3302)
						)
						(arc
							(start -0.4318 -0.3302)
							(mid -0.402042 -0.402042)
							(end -0.3302 -0.4318)
						)
						(arc
							(start 0.3302 -0.4318)
							(mid 0.402042 -0.402042)
							(end 0.4318 -0.3302)
						)
						(arc
							(start 0.4318 0.3302)
							(mid 0.402042 0.402042)
							(end 0.3302 0.4318)
						)
					)
					(width 0)
					(fill yes)
				)
			)
		)
	)
	(footprint ""
		(layer "B.Cu")
		(at 241.6048 -56.007 90)
		(property "Reference" "C502"
			(at 0 0 90)
			(layer "B.SilkS")
			(hide yes)
			(effects
				(font
					(size 1.27 1.27)
				)
				(justify mirror)
			)
		)
		(property "Value" "SCD1U16V1KX-1-GP"
			(at 2.8321 -1.7399 90)
			(unlocked yes)
			(layer "B.Fab")
			(hide yes)
			(effects
				(font
					(size 1.016 1.016)
					(thickness 0.1524)
				)
				(justify mirror)
			)
		)
		(property "Device Type" "C0201H13"
			(at 2.8321 -3.2639 90)
			(unlocked yes)
			(layer "B.Fab")
			(hide yes)
			(effects
				(font
					(size 1.016 1.016)
					(thickness 0.1524)
				)
				(justify mirror)
			)
		)
		(duplicate_pad_numbers_are_jumpers no)
		(fp_rect
			(start 0.2794 0.6477)
			(end -0.2794 -0.6477)
			(stroke
				(width 0)
				(type default)
			)
			(fill no)
			(layer "B.CrtYd")
		)
		(fp_rect
			(start 0.2794 0.6477)
			(end -0.2794 -0.6477)
			(stroke
				(width 0)
				(type default)
			)
			(fill no)
			(layer "B.Fab")
		)
		(pad "1" smd custom
			(at 0 -0.2794 270)
			(size 0.0762 0.0762)
			(layers "B.Cu" "B.Mask" "B.Paste")
			(net "DUT_AVD_TX")
			(options
				(clearance outline)
				(anchor circle)
			)
			(primitives
				(gr_poly
					(pts
						(arc
							(start 0.1524 0.127)
							(mid 0.137521 0.162921)
							(end 0.1016 0.1778)
						)
						(arc
							(start -0.1016 0.1778)
							(mid -0.137521 0.162921)
							(end -0.1524 0.127)
						)
						(arc
							(start -0.1524 -0.127)
							(mid -0.137521 -0.162921)
							(end -0.1016 -0.1778)
						)
						(arc
							(start 0.1016 -0.1778)
							(mid 0.137521 -0.162921)
							(end 0.1524 -0.127)
						)
					)
					(width 0)
					(fill yes)
				)
			)
		)
		(pad "2" smd custom
			(at 0 0.2794 270)
			(size 0.0762 0.0762)
			(layers "B.Cu" "B.Mask" "B.Paste")
			(net "GND")
			(options
				(clearance outline)
				(anchor circle)
			)
			(primitives
				(gr_poly
					(pts
						(arc
							(start 0.1524 0.127)
							(mid 0.137521 0.162921)
							(end 0.1016 0.1778)
						)
						(arc
							(start -0.1016 0.1778)
							(mid -0.137521 0.162921)
							(end -0.1524 0.127)
						)
						(arc
							(start -0.1524 -0.127)
							(mid -0.137521 -0.162921)
							(end -0.1016 -0.1778)
						)
						(arc
							(start 0.1016 -0.1778)
							(mid 0.137521 -0.162921)
							(end 0.1524 -0.127)
						)
					)
					(width 0)
					(fill yes)
				)
			)
		)
	)
	(footprint ""
		(layer "B.Cu")
		(at 59.2074 -127.508 90)
		(property "Reference" "R457"
			(at 0 0 90)
			(layer "B.SilkS")
			(hide yes)
			(effects
				(font
					(size 1.27 1.27)
				)
				(justify mirror)
			)
		)
		(property "Value" "4K7R2F-GP"
			(at -0.064008 -3.993896 90)
			(unlocked yes)
			(layer "B.Fab")
			(hide yes)
			(effects
				(font
					(size 1.016 1.016)
					(thickness 0.1524)
				)
				(justify mirror)
			)
		)
		(property "Device Type" "R402H16"
			(at -0.064008 -5.517896 90)
			(unlocked yes)
			(layer "B.Fab")
			(hide yes)
			(effects
				(font
					(size 1.016 1.016)
					(thickness 0.1524)
				)
				(justify mirror)
			)
		)
		(duplicate_pad_numbers_are_jumpers no)
		(fp_line
			(start 0.508 -0.9398)
			(end 0.508 0.9398)
			(stroke
				(width 0.1524)
				(type default)
			)
			(layer "B.SilkS")
		)
		(fp_line
			(start -0.508 -0.9398)
			(end 0.508 -0.9398)
			(stroke
				(width 0.1524)
				(type default)
			)
			(layer "B.SilkS")
		)
		(fp_rect
			(start 0.508 0.9398)
			(end -0.508 -0.9398)
			(stroke
				(width 0)
				(type default)
			)
			(fill no)
			(layer "B.CrtYd")
		)
		(fp_rect
			(start 0.508 0.9398)
			(end -0.508 -0.9398)
			(stroke
				(width 0)
				(type default)
			)
			(fill no)
			(layer "B.Fab")
		)
		(pad "1" smd custom
			(at 0 -0.4445 270)
			(size 0.1397 0.1397)
			(layers "B.Cu" "B.Mask" "B.Paste")
			(net "BMC_I2C14_MINI8_SDA_S")
			(options
				(clearance outline)
				(anchor circle)
			)
			(primitives
				(gr_poly
					(pts
						(arc
							(start -0.1778 0.2794)
							(mid -0.249642 0.249642)
							(end -0.2794 0.1778)
						)
						(arc
							(start -0.2794 -0.1778)
							(mid -0.249642 -0.249642)
							(end -0.1778 -0.2794)
						)
						(arc
							(start 0.1778 -0.2794)
							(mid 0.249642 -0.249642)
							(end 0.2794 -0.1778)
						)
						(arc
							(start 0.2794 0.1778)
							(mid 0.249642 0.249642)
							(end 0.1778 0.2794)
						)
					)
					(width 0)
					(fill yes)
				)
			)
		)
		(pad "2" smd custom
			(at 0 0.4445 270)
			(size 0.1397 0.1397)
			(layers "B.Cu" "B.Mask" "B.Paste")
			(net "P3V3_STBY")
			(options
				(clearance outline)
				(anchor circle)
			)
			(primitives
				(gr_poly
					(pts
						(arc
							(start -0.1778 0.2794)
							(mid -0.249642 0.249642)
							(end -0.2794 0.1778)
						)
						(arc
							(start -0.2794 -0.1778)
							(mid -0.249642 -0.249642)
							(end -0.1778 -0.2794)
						)
						(arc
							(start 0.1778 -0.2794)
							(mid 0.249642 -0.249642)
							(end 0.2794 -0.1778)
						)
						(arc
							(start 0.2794 0.1778)
							(mid 0.249642 0.249642)
							(end 0.1778 0.2794)
						)
					)
					(width 0)
					(fill yes)
				)
			)
		)
	)
)
